(kicad_pcb
	(version 20260206)
	(generator "pcbnew")
	(generator_version "10.0")
	(general
		(thickness 1.6)
		(legacy_teardrops no)
	)
	(paper "A4")
	(title_block
		(title "03242023_DA0F0TMBIJ0_F0T_Motherboard_J_brd_V01_OCP.brd")
		(comment 1 "Grand Teton / footprints 4478-4483 of 6105")
	)
	(layers
		(0 "F.Cu" signal "TOP")
		(4 "In1.Cu" signal "GND")
		(6 "In2.Cu" signal "IN1")
		(8 "In3.Cu" signal "GND1")
		(10 "In4.Cu" signal "IN2")
		(12 "In5.Cu" signal "GND2")
		(14 "In6.Cu" signal "IN3")
		(16 "In7.Cu" signal "GND3")
		(18 "In8.Cu" signal "VCC")
		(20 "In9.Cu" signal "VCC1")
		(22 "In10.Cu" signal "GND4")
		(24 "In11.Cu" signal "IN4")
		(26 "In12.Cu" signal "GND5")
		(28 "In13.Cu" signal "IN5")
		(30 "In14.Cu" signal "GND6")
		(32 "In15.Cu" signal "IN6")
		(34 "In16.Cu" signal "GND7")
		(2 "B.Cu" signal "BOTTOM")
		(9 "F.Adhes" user "F.Adhesive")
		(11 "B.Adhes" user "B.Adhesive")
		(13 "F.Paste" user "Package Geometry/Pastemask Top")
		(15 "B.Paste" user "Package Geometry/Pastemask Bottom")
		(5 "F.SilkS" user "Ref Des/Silkscreen Top")
		(7 "B.SilkS" user "Ref Des/Silkscreen Bottom")
		(1 "F.Mask" user "Board Geometry/Soldermask Top")
		(3 "B.Mask" user "Board Geometry/Soldermask Bottom")
		(17 "Dwgs.User" user "User.Drawings")
		(19 "Cmts.User" user "User.Comments")
		(21 "Eco1.User" user "User.Eco1")
		(23 "Eco2.User" user "User.Eco2")
		(25 "Edge.Cuts" user "Board Geometry/Outline")
		(27 "Margin" user)
		(31 "F.CrtYd" user "Package Geometry/Place Bound Top")
		(29 "B.CrtYd" user "Package Geometry/Place Bound Bottom")
		(35 "F.Fab" user "Ref Des/Assembly Top")
		(33 "B.Fab" user "Ref Des/Assembly Bottom")
	)
	(footprint ""
		(layer "B.Cu")
		(at 236.851698 -123.871482 90)
		(property "Reference" "C206"
			(at 0 0 90)
			(layer "B.SilkS")
			(hide yes)
			(effects
				(font
					(size 1.27 1.27)
				)
				(justify mirror)
			)
		)
		(property "Value" ""
			(at 0 0 90)
			(layer "B.Fab")
			(effects
				(font
					(size 1.27 1.27)
				)
				(justify mirror)
			)
		)
		(duplicate_pad_numbers_are_jumpers no)
		(fp_line
			(start 0.7874 -0.4064)
			(end -0.7874 -0.4064)
			(stroke
				(width 0.1524)
				(type default)
			)
			(layer "B.SilkS")
		)
		(fp_line
			(start -0.7874 -0.4064)
			(end -0.7874 0.4064)
			(stroke
				(width 0.1524)
				(type default)
			)
			(layer "B.SilkS")
		)
		(fp_line
			(start 0.7874 0.4064)
			(end 0.7874 -0.4064)
			(stroke
				(width 0.1524)
				(type default)
			)
			(layer "B.SilkS")
		)
		(fp_line
			(start -0.7874 0.4064)
			(end 0.7874 0.4064)
			(stroke
				(width 0.1524)
				(type default)
			)
			(layer "B.SilkS")
		)
		(fp_line
			(start 0.67945 -0.305054)
			(end 0.12065 -0.305054)
			(stroke
				(width 0.1)
				(type default)
			)
			(layer "B.Fab")
		)
		(fp_line
			(start 0.12065 -0.305054)
			(end 0.12065 -0.2794)
			(stroke
				(width 0.1)
				(type default)
			)
			(layer "B.Fab")
		)
		(fp_line
			(start -0.12065 -0.3048)
			(end -0.67945 -0.3048)
			(stroke
				(width 0.1)
				(type default)
			)
			(layer "B.Fab")
		)
		(fp_line
			(start -0.67945 -0.3048)
			(end -0.67945 0.3048)
			(stroke
				(width 0.1)
				(type default)
			)
			(layer "B.Fab")
		)
		(fp_line
			(start 0.12065 -0.2794)
			(end -0.12065 -0.2794)
			(stroke
				(width 0.1)
				(type default)
			)
			(layer "B.Fab")
		)
		(fp_line
			(start -0.12065 -0.2794)
			(end -0.12065 -0.3048)
			(stroke
				(width 0.1)
				(type default)
			)
			(layer "B.Fab")
		)
		(fp_line
			(start 0.12065 0.2794)
			(end 0.12065 0.3048)
			(stroke
				(width 0.1)
				(type default)
			)
			(layer "B.Fab")
		)
		(fp_line
			(start -0.120396 0.2794)
			(end 0.12065 0.2794)
			(stroke
				(width 0.1)
				(type default)
			)
			(layer "B.Fab")
		)
		(fp_line
			(start 0.67945 0.3048)
			(end 0.67945 -0.305054)
			(stroke
				(width 0.1)
				(type default)
			)
			(layer "B.Fab")
		)
		(fp_line
			(start 0.12065 0.3048)
			(end 0.67945 0.3048)
			(stroke
				(width 0.1)
				(type default)
			)
			(layer "B.Fab")
		)
		(fp_line
			(start -0.120396 0.3048)
			(end -0.120396 0.2794)
			(stroke
				(width 0.1)
				(type default)
			)
			(layer "B.Fab")
		)
		(fp_line
			(start -0.67945 0.3048)
			(end -0.120396 0.3048)
			(stroke
				(width 0.1)
				(type default)
			)
			(layer "B.Fab")
		)
		(pad "1" smd circle
			(at 0.40005 0 270)
			(size 0 0)
			(layers "B.Cu" "B.Mask" "B.Paste")
			(net "P3V3_DB2000_VDD")
		)
		(pad "2" smd circle
			(at -0.40005 0 270)
			(size 0 0)
			(layers "B.Cu" "B.Mask" "B.Paste")
			(net "GND")
		)
	)
	(footprint ""
		(layer "B.Cu")
		(at 449.5546 -10.594086 90)
		(property "Reference" "R423"
			(at 0 0 90)
			(layer "B.SilkS")
			(hide yes)
			(effects
				(font
					(size 1.27 1.27)
				)
				(justify mirror)
			)
		)
		(property "Value" ""
			(at 0 0 90)
			(layer "B.Fab")
			(effects
				(font
					(size 1.27 1.27)
				)
				(justify mirror)
			)
		)
		(duplicate_pad_numbers_are_jumpers no)
		(fp_line
			(start 0.7874 -0.4064)
			(end -0.7874 -0.4064)
			(stroke
				(width 0.1524)
				(type default)
			)
			(layer "B.SilkS")
		)
		(fp_line
			(start -0.7874 -0.4064)
			(end -0.7874 0.4064)
			(stroke
				(width 0.1524)
				(type default)
			)
			(layer "B.SilkS")
		)
		(fp_line
			(start 0.7874 0.4064)
			(end 0.7874 -0.4064)
			(stroke
				(width 0.1524)
				(type default)
			)
			(layer "B.SilkS")
		)
		(fp_line
			(start -0.7874 0.4064)
			(end 0.7874 0.4064)
			(stroke
				(width 0.1524)
				(type default)
			)
			(layer "B.SilkS")
		)
		(fp_line
			(start 0.67945 -0.305054)
			(end 0.12065 -0.305054)
			(stroke
				(width 0.1)
				(type default)
			)
			(layer "B.Fab")
		)
		(fp_line
			(start 0.12065 -0.305054)
			(end 0.12065 -0.2794)
			(stroke
				(width 0.1)
				(type default)
			)
			(layer "B.Fab")
		)
		(fp_line
			(start -0.12065 -0.3048)
			(end -0.67945 -0.3048)
			(stroke
				(width 0.1)
				(type default)
			)
			(layer "B.Fab")
		)
		(fp_line
			(start -0.67945 -0.3048)
			(end -0.67945 0.3048)
			(stroke
				(width 0.1)
				(type default)
			)
			(layer "B.Fab")
		)
		(fp_line
			(start 0.12065 -0.2794)
			(end -0.12065 -0.2794)
			(stroke
				(width 0.1)
				(type default)
			)
			(layer "B.Fab")
		)
		(fp_line
			(start -0.12065 -0.2794)
			(end -0.12065 -0.3048)
			(stroke
				(width 0.1)
				(type default)
			)
			(layer "B.Fab")
		)
		(fp_line
			(start 0.12065 0.2794)
			(end 0.12065 0.3048)
			(stroke
				(width 0.1)
				(type default)
			)
			(layer "B.Fab")
		)
		(fp_line
			(start -0.120396 0.2794)
			(end 0.12065 0.2794)
			(stroke
				(width 0.1)
				(type default)
			)
			(layer "B.Fab")
		)
		(fp_line
			(start 0.67945 0.3048)
			(end 0.67945 -0.305054)
			(stroke
				(width 0.1)
				(type default)
			)
			(layer "B.Fab")
		)
		(fp_line
			(start 0.12065 0.3048)
			(end 0.67945 0.3048)
			(stroke
				(width 0.1)
				(type default)
			)
			(layer "B.Fab")
		)
		(fp_line
			(start -0.120396 0.3048)
			(end -0.120396 0.2794)
			(stroke
				(width 0.1)
				(type default)
			)
			(layer "B.Fab")
		)
		(fp_line
			(start -0.67945 0.3048)
			(end -0.120396 0.3048)
			(stroke
				(width 0.1)
				(type default)
			)
			(layer "B.Fab")
		)
		(pad "1" smd circle
			(at 0.40005 0 270)
			(size 0 0)
			(layers "B.Cu" "B.Mask" "B.Paste")
			(net "SGPIO_OCP_SFF_CLK")
		)
		(pad "2" smd circle
			(at -0.40005 0 270)
			(size 0 0)
			(layers "B.Cu" "B.Mask" "B.Paste")
			(net "P3V3_OCP_SFF")
		)
	)
	(footprint ""
		(layer "B.Cu")
		(at 178.10988 -102.707948)
		(property "Reference" "C1942"
			(at 0 0 0)
			(layer "B.SilkS")
			(hide yes)
			(effects
				(font
					(size 1.27 1.27)
				)
				(justify mirror)
			)
		)
		(property "Value" ""
			(at 0 0 0)
			(layer "B.Fab")
			(effects
				(font
					(size 1.27 1.27)
				)
				(justify mirror)
			)
		)
		(duplicate_pad_numbers_are_jumpers no)
		(fp_line
			(start -0.7874 -0.4064)
			(end -0.7874 0.4064)
			(stroke
				(width 0.1524)
				(type default)
			)
			(layer "B.SilkS")
		)
		(fp_line
			(start -0.7874 0.4064)
			(end 0.7874 0.4064)
			(stroke
				(width 0.1524)
				(type default)
			)
			(layer "B.SilkS")
		)
		(fp_line
			(start 0.7874 -0.4064)
			(end -0.7874 -0.4064)
			(stroke
				(width 0.1524)
				(type default)
			)
			(layer "B.SilkS")
		)
		(fp_line
			(start 0.7874 0.4064)
			(end 0.7874 -0.4064)
			(stroke
				(width 0.1524)
				(type default)
			)
			(layer "B.SilkS")
		)
		(fp_line
			(start -0.67945 -0.3048)
			(end -0.67945 0.3048)
			(stroke
				(width 0.1)
				(type default)
			)
			(layer "B.Fab")
		)
		(fp_line
			(start -0.67945 0.3048)
			(end -0.120396 0.3048)
			(stroke
				(width 0.1)
				(type default)
			)
			(layer "B.Fab")
		)
		(fp_line
			(start -0.12065 -0.3048)
			(end -0.67945 -0.3048)
			(stroke
				(width 0.1)
				(type default)
			)
			(layer "B.Fab")
		)
		(fp_line
			(start -0.12065 -0.2794)
			(end -0.12065 -0.3048)
			(stroke
				(width 0.1)
				(type default)
			)
			(layer "B.Fab")
		)
		(fp_line
			(start -0.120396 0.2794)
			(end 0.12065 0.2794)
			(stroke
				(width 0.1)
				(type default)
			)
			(layer "B.Fab")
		)
		(fp_line
			(start -0.120396 0.3048)
			(end -0.120396 0.2794)
			(stroke
				(width 0.1)
				(type default)
			)
			(layer "B.Fab")
		)
		(fp_line
			(start 0.12065 -0.305054)
			(end 0.12065 -0.2794)
			(stroke
				(width 0.1)
				(type default)
			)
			(layer "B.Fab")
		)
		(fp_line
			(start 0.12065 -0.2794)
			(end -0.12065 -0.2794)
			(stroke
				(width 0.1)
				(type default)
			)
			(layer "B.Fab")
		)
		(fp_line
			(start 0.12065 0.2794)
			(end 0.12065 0.3048)
			(stroke
				(width 0.1)
				(type default)
			)
			(layer "B.Fab")
		)
		(fp_line
			(start 0.12065 0.3048)
			(end 0.67945 0.3048)
			(stroke
				(width 0.1)
				(type default)
			)
			(layer "B.Fab")
		)
		(fp_line
			(start 0.67945 -0.305054)
			(end 0.12065 -0.305054)
			(stroke
				(width 0.1)
				(type default)
			)
			(layer "B.Fab")
		)
		(fp_line
			(start 0.67945 0.3048)
			(end 0.67945 -0.305054)
			(stroke
				(width 0.1)
				(type default)
			)
			(layer "B.Fab")
		)
		(pad "1" smd circle
			(at 0.40005 0 180)
			(size 0 0)
			(layers "B.Cu" "B.Mask" "B.Paste")
			(net "P3V3_AUX_FPGA_VCCIO4")
		)
		(pad "2" smd circle
			(at -0.40005 0 180)
			(size 0 0)
			(layers "B.Cu" "B.Mask" "B.Paste")
			(net "GND")
		)
	)
	(footprint ""
		(layer "B.Cu")
		(at 53.095652 -177.349404 180)
		(property "Reference" "PC433"
			(at 0 0 0)
			(layer "B.SilkS")
			(hide yes)
			(effects
				(font
					(size 1.27 1.27)
				)
				(justify mirror)
			)
		)
		(property "Value" ""
			(at 0 0 0)
			(layer "B.Fab")
			(effects
				(font
					(size 1.27 1.27)
				)
				(justify mirror)
			)
		)
		(duplicate_pad_numbers_are_jumpers no)
		(fp_line
			(start 1.524 0.762)
			(end 1.524 -0.762)
			(stroke
				(width 0.1524)
				(type default)
			)
			(layer "B.SilkS")
		)
		(fp_line
			(start 1.524 -0.762)
			(end -1.524 -0.762)
			(stroke
				(width 0.1524)
				(type default)
			)
			(layer "B.SilkS")
		)
		(fp_line
			(start -1.524 0.762)
			(end 1.524 0.762)
			(stroke
				(width 0.1524)
				(type default)
			)
			(layer "B.SilkS")
		)
		(fp_line
			(start -1.524 -0.762)
			(end -1.524 0.762)
			(stroke
				(width 0.1524)
				(type default)
			)
			(layer "B.SilkS")
		)
		(fp_line
			(start 1.1049 0.724916)
			(end -1.1049 0.724916)
			(stroke
				(width 0.1)
				(type default)
			)
			(layer "B.Fab")
		)
		(fp_line
			(start 1.1049 -0.724916)
			(end 1.1049 0.724916)
			(stroke
				(width 0.1)
				(type default)
			)
			(layer "B.Fab")
		)
		(fp_line
			(start -1.1049 0.724916)
			(end -1.1049 -0.724916)
			(stroke
				(width 0.1)
				(type default)
			)
			(layer "B.Fab")
		)
		(fp_line
			(start -1.1049 -0.724916)
			(end 1.1049 -0.724916)
			(stroke
				(width 0.1)
				(type default)
			)
			(layer "B.Fab")
		)
		(pad "1" smd rect
			(at 0.889 0 180)
			(size 1.016 1.27)
			(layers "B.Cu" "B.Mask" "B.Paste")
			(net "SW_P12V_PVCCINFAON_CPU1_FLT")
		)
		(pad "2" smd rect
			(at -0.889 0 180)
			(size 1.016 1.27)
			(layers "B.Cu" "B.Mask" "B.Paste")
			(net "GND")
		)
	)
	(footprint ""
		(layer "B.Cu")
		(at 113.91773 -415.671254)
		(property "Reference" "C2332"
			(at 0 0 0)
			(layer "B.SilkS")
			(hide yes)
			(effects
				(font
					(size 1.27 1.27)
				)
				(justify mirror)
			)
		)
		(property "Value" ""
			(at 0 0 0)
			(layer "B.Fab")
			(effects
				(font
					(size 1.27 1.27)
				)
				(justify mirror)
			)
		)
		(duplicate_pad_numbers_are_jumpers no)
		(fp_line
			(start -1.2954 -0.5842)
			(end -1.2954 0.5842)
			(stroke
				(width 0.1524)
				(type default)
			)
			(layer "B.SilkS")
		)
		(fp_line
			(start -1.2954 0.5842)
			(end 1.2954 0.5842)
			(stroke
				(width 0.1524)
				(type default)
			)
			(layer "B.SilkS")
		)
		(fp_line
			(start 0 -0.5842)
			(end 0 0.5842)
			(stroke
				(width 0.1524)
				(type default)
			)
			(layer "B.SilkS")
		)
		(fp_line
			(start 1.2954 -0.5842)
			(end -1.2954 -0.5842)
			(stroke
				(width 0.1524)
				(type default)
			)
			(layer "B.SilkS")
		)
		(fp_line
			(start 1.2954 0.5842)
			(end 1.2954 -0.5842)
			(stroke
				(width 0.1524)
				(type default)
			)
			(layer "B.SilkS")
		)
		(fp_line
			(start -1.1938 -0.4064)
			(end -1.1938 0.4064)
			(stroke
				(width 0.1)
				(type default)
			)
			(layer "B.Fab")
		)
		(fp_line
			(start -1.1938 0.4064)
			(end -0.8636 0.4064)
			(stroke
				(width 0.1)
				(type default)
			)
			(layer "B.Fab")
		)
		(fp_line
			(start -0.8636 -0.4572)
			(end -0.8636 -0.4064)
			(stroke
				(width 0.1)
				(type default)
			)
			(layer "B.Fab")
		)
		(fp_line
			(start -0.8636 -0.4064)
			(end -1.1938 -0.4064)
			(stroke
				(width 0.1)
				(type default)
			)
			(layer "B.Fab")
		)
		(fp_line
			(start -0.8636 0.4064)
			(end -0.8636 0.4572)
			(stroke
				(width 0.1)
				(type default)
			)
			(layer "B.Fab")
		)
		(fp_line
			(start -0.8636 0.4572)
			(end 0.8636 0.4572)
			(stroke
				(width 0.1)
				(type default)
			)
			(layer "B.Fab")
		)
		(fp_line
			(start 0.8636 -0.4572)
			(end -0.8636 -0.4572)
			(stroke
				(width 0.1)
				(type default)
			)
			(layer "B.Fab")
		)
		(fp_line
			(start 0.8636 -0.4064)
			(end 0.8636 -0.4572)
			(stroke
				(width 0.1)
				(type default)
			)
			(layer "B.Fab")
		)
		(fp_line
			(start 0.8636 0.4064)
			(end 1.1938 0.4064)
			(stroke
				(width 0.1)
				(type default)
			)
			(layer "B.Fab")
		)
		(fp_line
			(start 0.8636 0.4572)
			(end 0.8636 0.4064)
			(stroke
				(width 0.1)
				(type default)
			)
			(layer "B.Fab")
		)
		(fp_line
			(start 1.1938 -0.4064)
			(end 0.8636 -0.4064)
			(stroke
				(width 0.1)
				(type default)
			)
			(layer "B.Fab")
		)
		(fp_line
			(start 1.1938 0.4064)
			(end 1.1938 -0.4064)
			(stroke
				(width 0.1)
				(type default)
			)
			(layer "B.Fab")
		)
		(pad "1" smd rect
			(at 0.7366 0 270)
			(size 0.7112 0.8128)
			(layers "B.Cu" "B.Mask" "B.Paste")
			(net "P3V3_9ZXL045_VDDR")
		)
		(pad "2" smd rect
			(at -0.7366 0 270)
			(size 0.7112 0.8128)
			(layers "B.Cu" "B.Mask" "B.Paste")
			(net "GND")
		)
	)
	(footprint ""
		(layer "B.Cu")
		(at 456.543918 -314.80506 90)
		(property "Reference" "R2501"
			(at 0 0 90)
			(layer "B.SilkS")
			(hide yes)
			(effects
				(font
					(size 1.27 1.27)
				)
				(justify mirror)
			)
		)
		(property "Value" ""
			(at 0 0 90)
			(layer "B.Fab")
			(effects
				(font
					(size 1.27 1.27)
				)
				(justify mirror)
			)
		)
		(duplicate_pad_numbers_are_jumpers no)
		(fp_line
			(start 0.7874 -0.4064)
			(end -0.7874 -0.4064)
			(stroke
				(width 0.1524)
				(type default)
			)
			(layer "B.SilkS")
		)
		(fp_line
			(start -0.7874 -0.4064)
			(end -0.7874 0.4064)
			(stroke
				(width 0.1524)
				(type default)
			)
			(layer "B.SilkS")
		)
		(fp_line
			(start 0.7874 0.4064)
			(end 0.7874 -0.4064)
			(stroke
				(width 0.1524)
				(type default)
			)
			(layer "B.SilkS")
		)
		(fp_line
			(start -0.7874 0.4064)
			(end 0.7874 0.4064)
			(stroke
				(width 0.1524)
				(type default)
			)
			(layer "B.SilkS")
		)
		(fp_line
			(start 0.67945 -0.305054)
			(end 0.12065 -0.305054)
			(stroke
				(width 0.1)
				(type default)
			)
			(layer "B.Fab")
		)
		(fp_line
			(start 0.12065 -0.305054)
			(end 0.12065 -0.2794)
			(stroke
				(width 0.1)
				(type default)
			)
			(layer "B.Fab")
		)
		(fp_line
			(start -0.12065 -0.3048)
			(end -0.67945 -0.3048)
			(stroke
				(width 0.1)
				(type default)
			)
			(layer "B.Fab")
		)
		(fp_line
			(start -0.67945 -0.3048)
			(end -0.67945 0.3048)
			(stroke
				(width 0.1)
				(type default)
			)
			(layer "B.Fab")
		)
		(fp_line
			(start 0.12065 -0.2794)
			(end -0.12065 -0.2794)
			(stroke
				(width 0.1)
				(type default)
			)
			(layer "B.Fab")
		)
		(fp_line
			(start -0.12065 -0.2794)
			(end -0.12065 -0.3048)
			(stroke
				(width 0.1)
				(type default)
			)
			(layer "B.Fab")
		)
		(fp_line
			(start 0.12065 0.2794)
			(end 0.12065 0.3048)
			(stroke
				(width 0.1)
				(type default)
			)
			(layer "B.Fab")
		)
		(fp_line
			(start -0.120396 0.2794)
			(end 0.12065 0.2794)
			(stroke
				(width 0.1)
				(type default)
			)
			(layer "B.Fab")
		)
		(fp_line
			(start 0.67945 0.3048)
			(end 0.67945 -0.305054)
			(stroke
				(width 0.1)
				(type default)
			)
			(layer "B.Fab")
		)
		(fp_line
			(start 0.12065 0.3048)
			(end 0.67945 0.3048)
			(stroke
				(width 0.1)
				(type default)
			)
			(layer "B.Fab")
		)
		(fp_line
			(start -0.120396 0.3048)
			(end -0.120396 0.2794)
			(stroke
				(width 0.1)
				(type default)
			)
			(layer "B.Fab")
		)
		(fp_line
			(start -0.67945 0.3048)
			(end -0.120396 0.3048)
			(stroke
				(width 0.1)
				(type default)
			)
			(layer "B.Fab")
		)
		(pad "1" smd circle
			(at 0.40005 0 270)
			(size 0 0)
			(layers "B.Cu" "B.Mask" "B.Paste")
			(net "PWRGD_FAIL_CPU0_GH_R1")
		)
		(pad "2" smd circle
			(at -0.40005 0 270)
			(size 0 0)
			(layers "B.Cu" "B.Mask" "B.Paste")
			(net "PWRGD_FAIL_CPU0_GH_R")
		)
	)
)
